# S9S_MB_2U (Grand Teton) — schematic netlist excerpt (pin names and nets, part order shuffled) for the footprints in the layout excerpt that follows; sources: Cadence DE-HDL packaged netlist, KiCad conversion of 03242023_DA0F0TMBIJ0_F0T_Motherboard_J_brd_V01_OCP.brd

R480  Q_RES  0 5% CHIP  pkg 0402LF  page 239 : A = JTAG_DBP_TMS ; B = JTAG_DBP_FB_TMS
PC221  Q_CAP  0.1UF 25V 10% X7R  pkg 0402  page 274 : A = PVCCINFAON_CPU0_VIN_CSNIN ; B = GND

(kicad_pcb
	(version 20260206)
	(generator "pcbnew")
	(generator_version "10.0")
	(general
		(thickness 1.6)
		(legacy_teardrops no)
	)
	(paper "A4")
	(title_block
		(title "03242023_DA0F0TMBIJ0_F0T_Motherboard_J_brd_V01_OCP.brd")
		(comment 1 "Grand Teton / footprints 1947-1948 of 6105")
	)
	(layers
		(0 "F.Cu" signal "TOP")
		(4 "In1.Cu" signal "GND")
		(6 "In2.Cu" signal "IN1")
		(8 "In3.Cu" signal "GND1")
		(10 "In4.Cu" signal "IN2")
		(12 "In5.Cu" signal "GND2")
		(14 "In6.Cu" signal "IN3")
		(16 "In7.Cu" signal "GND3")
		(18 "In8.Cu" signal "VCC")
		(20 "In9.Cu" signal "VCC1")
		(22 "In10.Cu" signal "GND4")
		(24 "In11.Cu" signal "IN4")
		(26 "In12.Cu" signal "GND5")
		(28 "In13.Cu" signal "IN5")
		(30 "In14.Cu" signal "GND6")
		(32 "In15.Cu" signal "IN6")
		(34 "In16.Cu" signal "GND7")
		(2 "B.Cu" signal "BOTTOM")
		(9 "F.Adhes" user "F.Adhesive")
		(11 "B.Adhes" user "B.Adhesive")
		(13 "F.Paste" user "Package Geometry/Pastemask Top")
		(15 "B.Paste" user "Package Geometry/Pastemask Bottom")
		(5 "F.SilkS" user "Ref Des/Silkscreen Top")
		(7 "B.SilkS" user "Ref Des/Silkscreen Bottom")
		(1 "F.Mask" user "Board Geometry/Soldermask Top")
		(3 "B.Mask" user "Board Geometry/Soldermask Bottom")
		(17 "Dwgs.User" user "User.Drawings")
		(19 "Cmts.User" user "User.Comments")
		(21 "Eco1.User" user "User.Eco1")
		(23 "Eco2.User" user "User.Eco2")
		(25 "Edge.Cuts" user "Board Geometry/Outline")
		(27 "Margin" user)
		(31 "F.CrtYd" user "Package Geometry/Place Bound Top")
		(29 "B.CrtYd" user "Package Geometry/Place Bound Bottom")
		(35 "F.Fab" user "Ref Des/Assembly Top")
		(33 "B.Fab" user "Ref Des/Assembly Bottom")
	)
	(footprint ""
		(layer "F.Cu")
		(at 373.577358 -92.962984 90)
		(property "Reference" "R480"
			(at 0 0 90)
			(layer "F.SilkS")
			(hide yes)
			(effects
				(font
					(size 1.27 1.27)
				)
			)
		)
		(property "Value" ""
			(at 0 0 90)
			(layer "F.Fab")
			(effects
				(font
					(size 1.27 1.27)
				)
			)
		)
		(duplicate_pad_numbers_are_jumpers no)
		(fp_line
			(start 0.7874 -0.4064)
			(end 0.7874 0.4064)
			(stroke
				(width 0.1524)
				(type default)
			)
			(layer "F.SilkS")
		)
		(fp_line
			(start -0.7874 -0.4064)
			(end 0.7874 -0.4064)
			(stroke
				(width 0.1524)
				(type default)
			)
			(layer "F.SilkS")
		)
		(fp_line
			(start 0.7874 0.4064)
			(end -0.7874 0.4064)
			(stroke
				(width 0.1524)
				(type default)
			)
			(layer "F.SilkS")
		)
		(fp_line
			(start -0.7874 0.4064)
			(end -0.7874 -0.4064)
			(stroke
				(width 0.1524)
				(type default)
			)
			(layer "F.SilkS")
		)
		(fp_line
			(start -0.12065 -0.305054)
			(end -0.12065 -0.2794)
			(stroke
				(width 0.1)
				(type default)
			)
			(layer "F.Fab")
		)
		(fp_line
			(start -0.67945 -0.305054)
			(end -0.12065 -0.305054)
			(stroke
				(width 0.1)
				(type default)
			)
			(layer "F.Fab")
		)
		(fp_line
			(start 0.67945 -0.3048)
			(end 0.67945 0.3048)
			(stroke
				(width 0.1)
				(type default)
			)
			(layer "F.Fab")
		)
		(fp_line
			(start 0.12065 -0.3048)
			(end 0.67945 -0.3048)
			(stroke
				(width 0.1)
				(type default)
			)
			(layer "F.Fab")
		)
		(fp_line
			(start 0.12065 -0.2794)
			(end 0.12065 -0.3048)
			(stroke
				(width 0.1)
				(type default)
			)
			(layer "F.Fab")
		)
		(fp_line
			(start -0.12065 -0.2794)
			(end 0.12065 -0.2794)
			(stroke
				(width 0.1)
				(type default)
			)
			(layer "F.Fab")
		)
		(fp_line
			(start 0.120396 0.2794)
			(end -0.12065 0.2794)
			(stroke
				(width 0.1)
				(type default)
			)
			(layer "F.Fab")
		)
		(fp_line
			(start -0.12065 0.2794)
			(end -0.12065 0.3048)
			(stroke
				(width 0.1)
				(type default)
			)
			(layer "F.Fab")
		)
		(fp_line
			(start 0.67945 0.3048)
			(end 0.120396 0.3048)
			(stroke
				(width 0.1)
				(type default)
			)
			(layer "F.Fab")
		)
		(fp_line
			(start 0.120396 0.3048)
			(end 0.120396 0.2794)
			(stroke
				(width 0.1)
				(type default)
			)
			(layer "F.Fab")
		)
		(fp_line
			(start -0.12065 0.3048)
			(end -0.67945 0.3048)
			(stroke
				(width 0.1)
				(type default)
			)
			(layer "F.Fab")
		)
		(fp_line
			(start -0.67945 0.3048)
			(end -0.67945 -0.305054)
			(stroke
				(width 0.1)
				(type default)
			)
			(layer "F.Fab")
		)
		(pad "1" smd circle
			(at -0.40005 0 90)
			(size 0 0)
			(layers "F.Cu" "F.Mask" "F.Paste")
			(net "JTAG_DBP_TMS")
		)
		(pad "2" smd circle
			(at 0.40005 0 90)
			(size 0 0)
			(layers "F.Cu" "F.Mask" "F.Paste")
			(net "JTAG_DBP_FB_TMS")
		)
	)
	(footprint ""
		(layer "F.Cu")
		(at 420.682166 -135.146034 180)
		(property "Reference" "PC221"
			(at 0 0 180)
			(layer "F.SilkS")
			(hide yes)
			(effects
				(font
					(size 1.27 1.27)
				)
			)
		)
		(property "Value" ""
			(at 0 0 180)
			(layer "F.Fab")
			(effects
				(font
					(size 1.27 1.27)
				)
			)
		)
		(duplicate_pad_numbers_are_jumpers no)
		(fp_line
			(start 0.7874 0.4064)
			(end -0.7874 0.4064)
			(stroke
				(width 0.1524)
				(type default)
			)
			(layer "F.SilkS")
		)
		(fp_line
			(start 0.7874 -0.4064)
			(end 0.7874 0.4064)
			(stroke
				(width 0.1524)
				(type default)
			)
			(layer "F.SilkS")
		)
		(fp_line
			(start -0.7874 0.4064)
			(end -0.7874 -0.4064)
			(stroke
				(width 0.1524)
				(type default)
			)
			(layer "F.SilkS")
		)
		(fp_line
			(start -0.7874 -0.4064)
			(end 0.7874 -0.4064)
			(stroke
				(width 0.1524)
				(type default)
			)
			(layer "F.SilkS")
		)
		(fp_line
			(start 0.67945 0.3048)
			(end 0.120396 0.3048)
			(stroke
				(width 0.1)
				(type default)
			)
			(layer "F.Fab")
		)
		(fp_line
			(start 0.67945 -0.3048)
			(end 0.67945 0.3048)
			(stroke
				(width 0.1)
				(type default)
			)
			(layer "F.Fab")
		)
		(fp_line
			(start 0.12065 -0.2794)
			(end 0.12065 -0.3048)
			(stroke
				(width 0.1)
				(type default)
			)
			(layer "F.Fab")
		)
		(fp_line
			(start 0.12065 -0.3048)
			(end 0.67945 -0.3048)
			(stroke
				(width 0.1)
				(type default)
			)
			(layer "F.Fab")
		)
		(fp_line
			(start 0.120396 0.3048)
			(end 0.120396 0.2794)
			(stroke
				(width 0.1)
				(type default)
			)
			(layer "F.Fab")
		)
		(fp_line
			(start 0.120396 0.2794)
			(end -0.12065 0.2794)
			(stroke
				(width 0.1)
				(type default)
			)
			(layer "F.Fab")
		)
		(fp_line
			(start -0.12065 0.3048)
			(end -0.67945 0.3048)
			(stroke
				(width 0.1)
				(type default)
			)
			(layer "F.Fab")
		)
		(fp_line
			(start -0.12065 0.2794)
			(end -0.12065 0.3048)
			(stroke
				(width 0.1)
				(type default)
			)
			(layer "F.Fab")
		)
		(fp_line
			(start -0.12065 -0.2794)
			(end 0.12065 -0.2794)
			(stroke
				(width 0.1)
				(type default)
			)
			(layer "F.Fab")
		)
		(fp_line
			(start -0.12065 -0.305054)
			(end -0.12065 -0.2794)
			(stroke
				(width 0.1)
				(type default)
			)
			(layer "F.Fab")
		)
		(fp_line
			(start -0.67945 0.3048)
			(end -0.67945 -0.305054)
			(stroke
				(width 0.1)
				(type default)
			)
			(layer "F.Fab")
		)
		(fp_line
			(start -0.67945 -0.305054)
			(end -0.12065 -0.305054)
			(stroke
				(width 0.1)
				(type default)
			)
			(layer "F.Fab")
		)
		(pad "1" smd circle
			(at -0.40005 0 180)
			(size 0 0)
			(layers "F.Cu" "F.Mask" "F.Paste")
			(net "PVCCINFAON_CPU0_VIN_CSNIN")
		)
		(pad "2" smd circle
			(at 0.40005 0 180)
			(size 0 0)
			(layers "F.Cu" "F.Mask" "F.Paste")
			(net "GND")
		)
	)
)
